# T6G (Grand Teton) — schematic netlist excerpt (pin names and nets, part order shuffled) for the footprints in the layout excerpt that follows; sources: Cadence DE-HDL packaged netlist, KiCad conversion of 04192023_DAF0TMB3IC0_F0TG_MB_C_brd_V02_OCP.brd

R3867  Q_RES  0 5% EMPTY  pkg 0402LF  page 140 : A = P12V_OCP_SENSE_2 ; B = P12V_OCP_V3_2_ISENSE_MAM_MAM
R1486  Q_RES  0 5% CHIP  pkg 0402LF  page 134 : A = P12V_OCP_SFF_BUF_EN_R ; B = P3V3_OCP_EN_1_R

(kicad_pcb
	(version 20260206)
	(generator "pcbnew")
	(generator_version "10.0")
	(general
		(thickness 1.6)
		(legacy_teardrops no)
	)
	(paper "A4")
	(title_block
		(title "04192023_DAF0TMB3IC0_F0TG_MB_C_brd_V02_OCP.brd")
		(comment 1 "Grand Teton / footprints 3600-3601 of 8354")
	)
	(layers
		(0 "F.Cu" signal "TOP")
		(4 "In1.Cu" signal "GND")
		(6 "In2.Cu" signal "IN1")
		(8 "In3.Cu" signal "GND1")
		(10 "In4.Cu" signal "IN2")
		(12 "In5.Cu" signal "GND2")
		(14 "In6.Cu" signal "IN3")
		(16 "In7.Cu" signal "GND3")
		(18 "In8.Cu" signal "VCC")
		(20 "In9.Cu" signal "VCC1")
		(22 "In10.Cu" signal "GND4")
		(24 "In11.Cu" signal "IN4")
		(26 "In12.Cu" signal "GND5")
		(28 "In13.Cu" signal "IN5")
		(30 "In14.Cu" signal "GND6")
		(32 "In15.Cu" signal "IN6")
		(34 "In16.Cu" signal "GND7")
		(2 "B.Cu" signal "BOTTOM")
		(9 "F.Adhes" user "F.Adhesive")
		(11 "B.Adhes" user "B.Adhesive")
		(13 "F.Paste" user "Package Geometry/Pastemask Top")
		(15 "B.Paste" user "Package Geometry/Pastemask Bottom")
		(5 "F.SilkS" user "Ref Des/Silkscreen Top")
		(7 "B.SilkS" user "Ref Des/Silkscreen Bottom")
		(1 "F.Mask" user "Board Geometry/Soldermask Top")
		(3 "B.Mask" user "Board Geometry/Soldermask Bottom")
		(17 "Dwgs.User" user "User.Drawings")
		(19 "Cmts.User" user "User.Comments")
		(21 "Eco1.User" user "User.Eco1")
		(23 "Eco2.User" user "User.Eco2")
		(25 "Edge.Cuts" user "Board Geometry/Outline")
		(27 "Margin" user)
		(31 "F.CrtYd" user "Package Geometry/Place Bound Top")
		(29 "B.CrtYd" user "Package Geometry/Place Bound Bottom")
		(35 "F.Fab" user "Ref Des/Assembly Top")
		(33 "B.Fab" user "Ref Des/Assembly Bottom")
	)
	(footprint ""
		(layer "F.Cu")
		(at 453.169782 -39.95674 90)
		(property "Reference" "R1486"
			(at 0 0 90)
			(layer "F.SilkS")
			(hide yes)
			(effects
				(font
					(size 1.27 1.27)
				)
			)
		)
		(property "Value" ""
			(at 0 0 90)
			(layer "F.Fab")
			(effects
				(font
					(size 1.27 1.27)
				)
			)
		)
		(duplicate_pad_numbers_are_jumpers no)
		(fp_line
			(start 0.7874 -0.4064)
			(end 0.7874 0.4064)
			(stroke
				(width 0.1524)
				(type default)
			)
			(layer "F.SilkS")
		)
		(fp_line
			(start -0.7874 -0.4064)
			(end 0.7874 -0.4064)
			(stroke
				(width 0.1524)
				(type default)
			)
			(layer "F.SilkS")
		)
		(fp_line
			(start 0.7874 0.4064)
			(end -0.7874 0.4064)
			(stroke
				(width 0.1524)
				(type default)
			)
			(layer "F.SilkS")
		)
		(fp_line
			(start -0.7874 0.4064)
			(end -0.7874 -0.4064)
			(stroke
				(width 0.1524)
				(type default)
			)
			(layer "F.SilkS")
		)
		(fp_line
			(start -0.12065 -0.305054)
			(end -0.12065 -0.2794)
			(stroke
				(width 0.1)
				(type default)
			)
			(layer "F.Fab")
		)
		(fp_line
			(start -0.67945 -0.305054)
			(end -0.12065 -0.305054)
			(stroke
				(width 0.1)
				(type default)
			)
			(layer "F.Fab")
		)
		(fp_line
			(start 0.67945 -0.3048)
			(end 0.67945 0.3048)
			(stroke
				(width 0.1)
				(type default)
			)
			(layer "F.Fab")
		)
		(fp_line
			(start 0.12065 -0.3048)
			(end 0.67945 -0.3048)
			(stroke
				(width 0.1)
				(type default)
			)
			(layer "F.Fab")
		)
		(fp_line
			(start 0.12065 -0.2794)
			(end 0.12065 -0.3048)
			(stroke
				(width 0.1)
				(type default)
			)
			(layer "F.Fab")
		)
		(fp_line
			(start -0.12065 -0.2794)
			(end 0.12065 -0.2794)
			(stroke
				(width 0.1)
				(type default)
			)
			(layer "F.Fab")
		)
		(fp_line
			(start 0.120396 0.2794)
			(end -0.12065 0.2794)
			(stroke
				(width 0.1)
				(type default)
			)
			(layer "F.Fab")
		)
		(fp_line
			(start -0.12065 0.2794)
			(end -0.12065 0.3048)
			(stroke
				(width 0.1)
				(type default)
			)
			(layer "F.Fab")
		)
		(fp_line
			(start 0.67945 0.3048)
			(end 0.120396 0.3048)
			(stroke
				(width 0.1)
				(type default)
			)
			(layer "F.Fab")
		)
		(fp_line
			(start 0.120396 0.3048)
			(end 0.120396 0.2794)
			(stroke
				(width 0.1)
				(type default)
			)
			(layer "F.Fab")
		)
		(fp_line
			(start -0.12065 0.3048)
			(end -0.67945 0.3048)
			(stroke
				(width 0.1)
				(type default)
			)
			(layer "F.Fab")
		)
		(fp_line
			(start -0.67945 0.3048)
			(end -0.67945 -0.305054)
			(stroke
				(width 0.1)
				(type default)
			)
			(layer "F.Fab")
		)
		(pad "1" smd circle
			(at -0.40005 0 90)
			(size 0 0)
			(layers "F.Cu" "F.Mask" "F.Paste")
			(net "P12V_OCP_SFF_BUF_EN_R")
		)
		(pad "2" smd circle
			(at 0.40005 0 90)
			(size 0 0)
			(layers "F.Cu" "F.Mask" "F.Paste")
			(net "P3V3_OCP_EN_1_R")
		)
	)
	(footprint ""
		(layer "F.Cu")
		(at 60.527438 -31.887922 -90)
		(property "Reference" "R3867"
			(at 0 0 270)
			(layer "F.SilkS")
			(hide yes)
			(effects
				(font
					(size 1.27 1.27)
				)
			)
		)
		(property "Value" ""
			(at 0 0 270)
			(layer "F.Fab")
			(effects
				(font
					(size 1.27 1.27)
				)
			)
		)
		(duplicate_pad_numbers_are_jumpers no)
		(fp_line
			(start -0.7874 0.4064)
			(end -0.7874 -0.4064)
			(stroke
				(width 0.1524)
				(type default)
			)
			(layer "F.SilkS")
		)
		(fp_line
			(start 0.7874 0.4064)
			(end -0.7874 0.4064)
			(stroke
				(width 0.1524)
				(type default)
			)
			(layer "F.SilkS")
		)
		(fp_line
			(start -0.7874 -0.4064)
			(end 0.7874 -0.4064)
			(stroke
				(width 0.1524)
				(type default)
			)
			(layer "F.SilkS")
		)
		(fp_line
			(start 0.7874 -0.4064)
			(end 0.7874 0.4064)
			(stroke
				(width 0.1524)
				(type default)
			)
			(layer "F.SilkS")
		)
		(fp_line
			(start -0.67945 0.3048)
			(end -0.67945 -0.305054)
			(stroke
				(width 0.1)
				(type default)
			)
			(layer "F.Fab")
		)
		(fp_line
			(start -0.12065 0.3048)
			(end -0.67945 0.3048)
			(stroke
				(width 0.1)
				(type default)
			)
			(layer "F.Fab")
		)
		(fp_line
			(start 0.120396 0.3048)
			(end 0.120396 0.2794)
			(stroke
				(width 0.1)
				(type default)
			)
			(layer "F.Fab")
		)
		(fp_line
			(start 0.67945 0.3048)
			(end 0.120396 0.3048)
			(stroke
				(width 0.1)
				(type default)
			)
			(layer "F.Fab")
		)
		(fp_line
			(start -0.12065 0.2794)
			(end -0.12065 0.3048)
			(stroke
				(width 0.1)
				(type default)
			)
			(layer "F.Fab")
		)
		(fp_line
			(start 0.120396 0.2794)
			(end -0.12065 0.2794)
			(stroke
				(width 0.1)
				(type default)
			)
			(layer "F.Fab")
		)
		(fp_line
			(start -0.12065 -0.2794)
			(end 0.12065 -0.2794)
			(stroke
				(width 0.1)
				(type default)
			)
			(layer "F.Fab")
		)
		(fp_line
			(start 0.12065 -0.2794)
			(end 0.12065 -0.3048)
			(stroke
				(width 0.1)
				(type default)
			)
			(layer "F.Fab")
		)
		(fp_line
			(start 0.12065 -0.3048)
			(end 0.67945 -0.3048)
			(stroke
				(width 0.1)
				(type default)
			)
			(layer "F.Fab")
		)
		(fp_line
			(start 0.67945 -0.3048)
			(end 0.67945 0.3048)
			(stroke
				(width 0.1)
				(type default)
			)
			(layer "F.Fab")
		)
		(fp_line
			(start -0.67945 -0.305054)
			(end -0.12065 -0.305054)
			(stroke
				(width 0.1)
				(type default)
			)
			(layer "F.Fab")
		)
		(fp_line
			(start -0.12065 -0.305054)
			(end -0.12065 -0.2794)
			(stroke
				(width 0.1)
				(type default)
			)
			(layer "F.Fab")
		)
		(pad "1" smd rect
			(at -0.40005 0 90)
			(size 0.4572 0.508)
			(layers "F.Cu" "F.Mask" "F.Paste")
			(net "P12V_OCP_SENSE_2")
		)
		(pad "2" smd rect
			(at 0.40005 0 90)
			(size 0.4572 0.508)
			(layers "F.Cu" "F.Mask" "F.Paste")
			(net "P12V_OCP_V3_2_ISENSE_MAM_MAM")
		)
	)
)
